# T6G (Grand Teton) — schematic netlist excerpt (pin names and nets, part order shuffled) for the footprints in the layout excerpt that follows; sources: Cadence DE-HDL packaged netlist, KiCad conversion of 04192023_DAF0TMB3IC0_F0TG_MB_C_brd_V02_OCP.brd

C6091  Q_CAP  27PF 50V 5% NPO  pkg 0402  page 179 : A = XTAL_USB_CPU0_HUB2_XIN ; B = GND
R6112  Q_RES  33.2 1% CHIP  pkg 0402LF  page 85 : A = RST_PERST_CPU0_SWB_N ; B = RST_PERST_CPU0_SWB_R_N

(kicad_pcb
	(version 20260206)
	(generator "pcbnew")
	(generator_version "10.0")
	(general
		(thickness 1.6)
		(legacy_teardrops no)
	)
	(paper "A4")
	(title_block
		(title "04192023_DAF0TMB3IC0_F0TG_MB_C_brd_V02_OCP.brd")
		(comment 1 "Grand Teton / footprints 338-339 of 8354")
	)
	(layers
		(0 "F.Cu" signal "TOP")
		(4 "In1.Cu" signal "GND")
		(6 "In2.Cu" signal "IN1")
		(8 "In3.Cu" signal "GND1")
		(10 "In4.Cu" signal "IN2")
		(12 "In5.Cu" signal "GND2")
		(14 "In6.Cu" signal "IN3")
		(16 "In7.Cu" signal "GND3")
		(18 "In8.Cu" signal "VCC")
		(20 "In9.Cu" signal "VCC1")
		(22 "In10.Cu" signal "GND4")
		(24 "In11.Cu" signal "IN4")
		(26 "In12.Cu" signal "GND5")
		(28 "In13.Cu" signal "IN5")
		(30 "In14.Cu" signal "GND6")
		(32 "In15.Cu" signal "IN6")
		(34 "In16.Cu" signal "GND7")
		(2 "B.Cu" signal "BOTTOM")
		(9 "F.Adhes" user "F.Adhesive")
		(11 "B.Adhes" user "B.Adhesive")
		(13 "F.Paste" user "Package Geometry/Pastemask Top")
		(15 "B.Paste" user "Package Geometry/Pastemask Bottom")
		(5 "F.SilkS" user "Ref Des/Silkscreen Top")
		(7 "B.SilkS" user "Ref Des/Silkscreen Bottom")
		(1 "F.Mask" user "Board Geometry/Soldermask Top")
		(3 "B.Mask" user "Board Geometry/Soldermask Bottom")
		(17 "Dwgs.User" user "User.Drawings")
		(19 "Cmts.User" user "User.Comments")
		(21 "Eco1.User" user "User.Eco1")
		(23 "Eco2.User" user "User.Eco2")
		(25 "Edge.Cuts" user "Board Geometry/Outline")
		(27 "Margin" user)
		(31 "F.CrtYd" user "Package Geometry/Place Bound Top")
		(29 "B.CrtYd" user "Package Geometry/Place Bound Bottom")
		(35 "F.Fab" user "Ref Des/Assembly Top")
		(33 "B.Fab" user "Ref Des/Assembly Bottom")
	)
	(footprint ""
		(layer "F.Cu")
		(at 107.137454 -25.183592)
		(property "Reference" "C6091"
			(at 0 0 0)
			(layer "F.SilkS")
			(hide yes)
			(effects
				(font
					(size 1.27 1.27)
				)
			)
		)
		(property "Value" ""
			(at 0 0 0)
			(layer "F.Fab")
			(effects
				(font
					(size 1.27 1.27)
				)
			)
		)
		(duplicate_pad_numbers_are_jumpers no)
		(fp_line
			(start -0.7874 -0.4064)
			(end 0.7874 -0.4064)
			(stroke
				(width 0.1524)
				(type default)
			)
			(layer "F.SilkS")
		)
		(fp_line
			(start -0.7874 0.4064)
			(end -0.7874 -0.4064)
			(stroke
				(width 0.1524)
				(type default)
			)
			(layer "F.SilkS")
		)
		(fp_line
			(start 0.7874 -0.4064)
			(end 0.7874 0.4064)
			(stroke
				(width 0.1524)
				(type default)
			)
			(layer "F.SilkS")
		)
		(fp_line
			(start 0.7874 0.4064)
			(end -0.7874 0.4064)
			(stroke
				(width 0.1524)
				(type default)
			)
			(layer "F.SilkS")
		)
		(fp_line
			(start -0.67945 -0.305054)
			(end -0.12065 -0.305054)
			(stroke
				(width 0.1)
				(type default)
			)
			(layer "F.Fab")
		)
		(fp_line
			(start -0.67945 0.3048)
			(end -0.67945 -0.305054)
			(stroke
				(width 0.1)
				(type default)
			)
			(layer "F.Fab")
		)
		(fp_line
			(start -0.12065 -0.305054)
			(end -0.12065 -0.2794)
			(stroke
				(width 0.1)
				(type default)
			)
			(layer "F.Fab")
		)
		(fp_line
			(start -0.12065 -0.2794)
			(end 0.12065 -0.2794)
			(stroke
				(width 0.1)
				(type default)
			)
			(layer "F.Fab")
		)
		(fp_line
			(start -0.12065 0.2794)
			(end -0.12065 0.3048)
			(stroke
				(width 0.1)
				(type default)
			)
			(layer "F.Fab")
		)
		(fp_line
			(start -0.12065 0.3048)
			(end -0.67945 0.3048)
			(stroke
				(width 0.1)
				(type default)
			)
			(layer "F.Fab")
		)
		(fp_line
			(start 0.120396 0.2794)
			(end -0.12065 0.2794)
			(stroke
				(width 0.1)
				(type default)
			)
			(layer "F.Fab")
		)
		(fp_line
			(start 0.120396 0.3048)
			(end 0.120396 0.2794)
			(stroke
				(width 0.1)
				(type default)
			)
			(layer "F.Fab")
		)
		(fp_line
			(start 0.12065 -0.3048)
			(end 0.67945 -0.3048)
			(stroke
				(width 0.1)
				(type default)
			)
			(layer "F.Fab")
		)
		(fp_line
			(start 0.12065 -0.2794)
			(end 0.12065 -0.3048)
			(stroke
				(width 0.1)
				(type default)
			)
			(layer "F.Fab")
		)
		(fp_line
			(start 0.67945 -0.3048)
			(end 0.67945 0.3048)
			(stroke
				(width 0.1)
				(type default)
			)
			(layer "F.Fab")
		)
		(fp_line
			(start 0.67945 0.3048)
			(end 0.120396 0.3048)
			(stroke
				(width 0.1)
				(type default)
			)
			(layer "F.Fab")
		)
		(pad "1" smd circle
			(at -0.40005 0)
			(size 0 0)
			(layers "F.Cu" "F.Mask" "F.Paste")
			(net "XTAL_USB_CPU0_HUB2_XIN")
		)
		(pad "2" smd circle
			(at 0.40005 0)
			(size 0 0)
			(layers "F.Cu" "F.Mask" "F.Paste")
			(net "GND")
		)
	)
	(footprint ""
		(layer "F.Cu")
		(at 200.952608 -115.657376)
		(property "Reference" "R6112"
			(at 0 0 0)
			(layer "F.SilkS")
			(hide yes)
			(effects
				(font
					(size 1.27 1.27)
				)
			)
		)
		(property "Value" ""
			(at 0 0 0)
			(layer "F.Fab")
			(effects
				(font
					(size 1.27 1.27)
				)
			)
		)
		(duplicate_pad_numbers_are_jumpers no)
		(fp_line
			(start -0.7874 -0.4064)
			(end 0.7874 -0.4064)
			(stroke
				(width 0.1524)
				(type default)
			)
			(layer "F.SilkS")
		)
		(fp_line
			(start -0.7874 0.4064)
			(end -0.7874 -0.4064)
			(stroke
				(width 0.1524)
				(type default)
			)
			(layer "F.SilkS")
		)
		(fp_line
			(start 0.7874 -0.4064)
			(end 0.7874 0.4064)
			(stroke
				(width 0.1524)
				(type default)
			)
			(layer "F.SilkS")
		)
		(fp_line
			(start 0.7874 0.4064)
			(end -0.7874 0.4064)
			(stroke
				(width 0.1524)
				(type default)
			)
			(layer "F.SilkS")
		)
		(fp_line
			(start -0.67945 -0.305054)
			(end -0.12065 -0.305054)
			(stroke
				(width 0.1)
				(type default)
			)
			(layer "F.Fab")
		)
		(fp_line
			(start -0.67945 0.3048)
			(end -0.67945 -0.305054)
			(stroke
				(width 0.1)
				(type default)
			)
			(layer "F.Fab")
		)
		(fp_line
			(start -0.12065 -0.305054)
			(end -0.12065 -0.2794)
			(stroke
				(width 0.1)
				(type default)
			)
			(layer "F.Fab")
		)
		(fp_line
			(start -0.12065 -0.2794)
			(end 0.12065 -0.2794)
			(stroke
				(width 0.1)
				(type default)
			)
			(layer "F.Fab")
		)
		(fp_line
			(start -0.12065 0.2794)
			(end -0.12065 0.3048)
			(stroke
				(width 0.1)
				(type default)
			)
			(layer "F.Fab")
		)
		(fp_line
			(start -0.12065 0.3048)
			(end -0.67945 0.3048)
			(stroke
				(width 0.1)
				(type default)
			)
			(layer "F.Fab")
		)
		(fp_line
			(start 0.120396 0.2794)
			(end -0.12065 0.2794)
			(stroke
				(width 0.1)
				(type default)
			)
			(layer "F.Fab")
		)
		(fp_line
			(start 0.120396 0.3048)
			(end 0.120396 0.2794)
			(stroke
				(width 0.1)
				(type default)
			)
			(layer "F.Fab")
		)
		(fp_line
			(start 0.12065 -0.3048)
			(end 0.67945 -0.3048)
			(stroke
				(width 0.1)
				(type default)
			)
			(layer "F.Fab")
		)
		(fp_line
			(start 0.12065 -0.2794)
			(end 0.12065 -0.3048)
			(stroke
				(width 0.1)
				(type default)
			)
			(layer "F.Fab")
		)
		(fp_line
			(start 0.67945 -0.3048)
			(end 0.67945 0.3048)
			(stroke
				(width 0.1)
				(type default)
			)
			(layer "F.Fab")
		)
		(fp_line
			(start 0.67945 0.3048)
			(end 0.120396 0.3048)
			(stroke
				(width 0.1)
				(type default)
			)
			(layer "F.Fab")
		)
		(pad "1" smd circle
			(at -0.40005 0)
			(size 0 0)
			(layers "F.Cu" "F.Mask" "F.Paste")
			(net "RST_PERST_CPU0_SWB_N")
		)
		(pad "2" smd circle
			(at 0.40005 0)
			(size 0 0)
			(layers "F.Cu" "F.Mask" "F.Paste")
			(net "RST_PERST_CPU0_SWB_R_N")
		)
	)
)
